# T6G (Grand Teton) — schematic netlist excerpt (pin names and nets, part order shuffled) for the footprints in the layout excerpt that follows; sources: Cadence DE-HDL packaged netlist, KiCad conversion of 04192023_DAF0TMB3IC0_F0TG_MB_C_brd_V02_OCP.brd

R1054  Q_RES  0 5% CHIP  pkg 0201LF  page 298 : A = RST_RT_CPU0_P2_RESET_N ; B = RST_RT_CPU0_P2_RESET_R_N
PC128  Q_CAP  0.1UF 25V 10% X7R  pkg 0402  page 192 : A = SW_PVDD_33_S5_BST_R ; B = SW_PVDD_33_S5_SW
R3577  Q_RES  0 5% CHIP  pkg 0402LF  page 237 : A = SMB_INA230_5_3V3AUX_SDA_R ; B = SMB_INA230_5_3V3AUX_SDA_R1

(kicad_pcb
	(version 20260206)
	(generator "pcbnew")
	(generator_version "10.0")
	(general
		(thickness 1.6)
		(legacy_teardrops no)
	)
	(paper "A4")
	(title_block
		(title "04192023_DAF0TMB3IC0_F0TG_MB_C_brd_V02_OCP.brd")
		(comment 1 "Grand Teton / footprints 349-351 of 8354")
	)
	(layers
		(0 "F.Cu" signal "TOP")
		(4 "In1.Cu" signal "GND")
		(6 "In2.Cu" signal "IN1")
		(8 "In3.Cu" signal "GND1")
		(10 "In4.Cu" signal "IN2")
		(12 "In5.Cu" signal "GND2")
		(14 "In6.Cu" signal "IN3")
		(16 "In7.Cu" signal "GND3")
		(18 "In8.Cu" signal "VCC")
		(20 "In9.Cu" signal "VCC1")
		(22 "In10.Cu" signal "GND4")
		(24 "In11.Cu" signal "IN4")
		(26 "In12.Cu" signal "GND5")
		(28 "In13.Cu" signal "IN5")
		(30 "In14.Cu" signal "GND6")
		(32 "In15.Cu" signal "IN6")
		(34 "In16.Cu" signal "GND7")
		(2 "B.Cu" signal "BOTTOM")
		(9 "F.Adhes" user "F.Adhesive")
		(11 "B.Adhes" user "B.Adhesive")
		(13 "F.Paste" user "Package Geometry/Pastemask Top")
		(15 "B.Paste" user "Package Geometry/Pastemask Bottom")
		(5 "F.SilkS" user "Ref Des/Silkscreen Top")
		(7 "B.SilkS" user "Ref Des/Silkscreen Bottom")
		(1 "F.Mask" user "Board Geometry/Soldermask Top")
		(3 "B.Mask" user "Board Geometry/Soldermask Bottom")
		(17 "Dwgs.User" user "User.Drawings")
		(19 "Cmts.User" user "User.Comments")
		(21 "Eco1.User" user "User.Eco1")
		(23 "Eco2.User" user "User.Eco2")
		(25 "Edge.Cuts" user "Board Geometry/Outline")
		(27 "Margin" user)
		(31 "F.CrtYd" user "Package Geometry/Place Bound Top")
		(29 "B.CrtYd" user "Package Geometry/Place Bound Bottom")
		(35 "F.Fab" user "Ref Des/Assembly Top")
		(33 "B.Fab" user "Ref Des/Assembly Bottom")
	)
	(footprint ""
		(layer "F.Cu")
		(at 213.54288 -32.857948 180)
		(property "Reference" "R3577"
			(at 0 0 180)
			(layer "F.SilkS")
			(hide yes)
			(effects
				(font
					(size 1.27 1.27)
				)
			)
		)
		(property "Value" ""
			(at 0 0 180)
			(layer "F.Fab")
			(effects
				(font
					(size 1.27 1.27)
				)
			)
		)
		(duplicate_pad_numbers_are_jumpers no)
		(fp_line
			(start 0.7874 0.4064)
			(end -0.7874 0.4064)
			(stroke
				(width 0.1524)
				(type default)
			)
			(layer "F.SilkS")
		)
		(fp_line
			(start 0.7874 -0.4064)
			(end 0.7874 0.4064)
			(stroke
				(width 0.1524)
				(type default)
			)
			(layer "F.SilkS")
		)
		(fp_line
			(start -0.7874 0.4064)
			(end -0.7874 -0.4064)
			(stroke
				(width 0.1524)
				(type default)
			)
			(layer "F.SilkS")
		)
		(fp_line
			(start -0.7874 -0.4064)
			(end 0.7874 -0.4064)
			(stroke
				(width 0.1524)
				(type default)
			)
			(layer "F.SilkS")
		)
		(fp_line
			(start 0.67945 0.3048)
			(end 0.120396 0.3048)
			(stroke
				(width 0.1)
				(type default)
			)
			(layer "F.Fab")
		)
		(fp_line
			(start 0.67945 -0.3048)
			(end 0.67945 0.3048)
			(stroke
				(width 0.1)
				(type default)
			)
			(layer "F.Fab")
		)
		(fp_line
			(start 0.12065 -0.2794)
			(end 0.12065 -0.3048)
			(stroke
				(width 0.1)
				(type default)
			)
			(layer "F.Fab")
		)
		(fp_line
			(start 0.12065 -0.3048)
			(end 0.67945 -0.3048)
			(stroke
				(width 0.1)
				(type default)
			)
			(layer "F.Fab")
		)
		(fp_line
			(start 0.120396 0.3048)
			(end 0.120396 0.2794)
			(stroke
				(width 0.1)
				(type default)
			)
			(layer "F.Fab")
		)
		(fp_line
			(start 0.120396 0.2794)
			(end -0.12065 0.2794)
			(stroke
				(width 0.1)
				(type default)
			)
			(layer "F.Fab")
		)
		(fp_line
			(start -0.12065 0.3048)
			(end -0.67945 0.3048)
			(stroke
				(width 0.1)
				(type default)
			)
			(layer "F.Fab")
		)
		(fp_line
			(start -0.12065 0.2794)
			(end -0.12065 0.3048)
			(stroke
				(width 0.1)
				(type default)
			)
			(layer "F.Fab")
		)
		(fp_line
			(start -0.12065 -0.2794)
			(end 0.12065 -0.2794)
			(stroke
				(width 0.1)
				(type default)
			)
			(layer "F.Fab")
		)
		(fp_line
			(start -0.12065 -0.305054)
			(end -0.12065 -0.2794)
			(stroke
				(width 0.1)
				(type default)
			)
			(layer "F.Fab")
		)
		(fp_line
			(start -0.67945 0.3048)
			(end -0.67945 -0.305054)
			(stroke
				(width 0.1)
				(type default)
			)
			(layer "F.Fab")
		)
		(fp_line
			(start -0.67945 -0.305054)
			(end -0.12065 -0.305054)
			(stroke
				(width 0.1)
				(type default)
			)
			(layer "F.Fab")
		)
		(pad "1" smd circle
			(at -0.40005 0 180)
			(size 0 0)
			(layers "F.Cu" "F.Mask" "F.Paste")
			(net "SMB_INA230_5_3V3AUX_SDA_R")
		)
		(pad "2" smd circle
			(at 0.40005 0 180)
			(size 0 0)
			(layers "F.Cu" "F.Mask" "F.Paste")
			(net "SMB_INA230_5_3V3AUX_SDA_R1")
		)
	)
	(footprint ""
		(layer "F.Cu")
		(at 399.350484 -403.285452 90)
		(property "Reference" "R1054"
			(at 0 0 90)
			(layer "F.SilkS")
			(hide yes)
			(effects
				(font
					(size 1.27 1.27)
				)
			)
		)
		(property "Value" ""
			(at 0 0 90)
			(layer "F.Fab")
			(effects
				(font
					(size 1.27 1.27)
				)
			)
		)
		(duplicate_pad_numbers_are_jumpers no)
		(fp_line
			(start 0.32512 -0.175006)
			(end 0.32512 0.175006)
			(stroke
				(width 0.1)
				(type default)
			)
			(layer "F.Fab")
		)
		(fp_line
			(start -0.32512 -0.175006)
			(end 0.32512 -0.175006)
			(stroke
				(width 0.1)
				(type default)
			)
			(layer "F.Fab")
		)
		(fp_line
			(start 0.32512 0.175006)
			(end -0.32512 0.175006)
			(stroke
				(width 0.1)
				(type default)
			)
			(layer "F.Fab")
		)
		(fp_line
			(start -0.32512 0.175006)
			(end -0.32512 -0.175006)
			(stroke
				(width 0.1)
				(type default)
			)
			(layer "F.Fab")
		)
		(pad "1" smd rect
			(at -0.2667 0 90)
			(size 0.3048 0.381)
			(layers "F.Cu" "F.Mask" "F.Paste")
			(net "RST_RT_CPU0_P2_RESET_N")
		)
		(pad "2" smd rect
			(at 0.2667 0 270)
			(size 0.3048 0.381)
			(layers "F.Cu" "F.Mask" "F.Paste")
			(net "RST_RT_CPU0_P2_RESET_R_N")
		)
	)
	(footprint ""
		(layer "F.Cu")
		(at 204.851 -337.439 -90)
		(property "Reference" "PC128"
			(at 0 0 270)
			(layer "F.SilkS")
			(hide yes)
			(effects
				(font
					(size 1.27 1.27)
				)
			)
		)
		(property "Value" ""
			(at 0 0 270)
			(layer "F.Fab")
			(effects
				(font
					(size 1.27 1.27)
				)
			)
		)
		(duplicate_pad_numbers_are_jumpers no)
		(fp_line
			(start -0.7874 0.4064)
			(end -0.7874 -0.4064)
			(stroke
				(width 0.1524)
				(type default)
			)
			(layer "F.SilkS")
		)
		(fp_line
			(start 0.7874 0.4064)
			(end -0.7874 0.4064)
			(stroke
				(width 0.1524)
				(type default)
			)
			(layer "F.SilkS")
		)
		(fp_line
			(start -0.7874 -0.4064)
			(end 0.7874 -0.4064)
			(stroke
				(width 0.1524)
				(type default)
			)
			(layer "F.SilkS")
		)
		(fp_line
			(start 0.7874 -0.4064)
			(end 0.7874 0.4064)
			(stroke
				(width 0.1524)
				(type default)
			)
			(layer "F.SilkS")
		)
		(fp_line
			(start -0.67945 0.3048)
			(end -0.67945 -0.305054)
			(stroke
				(width 0.1)
				(type default)
			)
			(layer "F.Fab")
		)
		(fp_line
			(start -0.12065 0.3048)
			(end -0.67945 0.3048)
			(stroke
				(width 0.1)
				(type default)
			)
			(layer "F.Fab")
		)
		(fp_line
			(start 0.120396 0.3048)
			(end 0.120396 0.2794)
			(stroke
				(width 0.1)
				(type default)
			)
			(layer "F.Fab")
		)
		(fp_line
			(start 0.67945 0.3048)
			(end 0.120396 0.3048)
			(stroke
				(width 0.1)
				(type default)
			)
			(layer "F.Fab")
		)
		(fp_line
			(start -0.12065 0.2794)
			(end -0.12065 0.3048)
			(stroke
				(width 0.1)
				(type default)
			)
			(layer "F.Fab")
		)
		(fp_line
			(start 0.120396 0.2794)
			(end -0.12065 0.2794)
			(stroke
				(width 0.1)
				(type default)
			)
			(layer "F.Fab")
		)
		(fp_line
			(start -0.12065 -0.2794)
			(end 0.12065 -0.2794)
			(stroke
				(width 0.1)
				(type default)
			)
			(layer "F.Fab")
		)
		(fp_line
			(start 0.12065 -0.2794)
			(end 0.12065 -0.3048)
			(stroke
				(width 0.1)
				(type default)
			)
			(layer "F.Fab")
		)
		(fp_line
			(start 0.12065 -0.3048)
			(end 0.67945 -0.3048)
			(stroke
				(width 0.1)
				(type default)
			)
			(layer "F.Fab")
		)
		(fp_line
			(start 0.67945 -0.3048)
			(end 0.67945 0.3048)
			(stroke
				(width 0.1)
				(type default)
			)
			(layer "F.Fab")
		)
		(fp_line
			(start -0.67945 -0.305054)
			(end -0.12065 -0.305054)
			(stroke
				(width 0.1)
				(type default)
			)
			(layer "F.Fab")
		)
		(fp_line
			(start -0.12065 -0.305054)
			(end -0.12065 -0.2794)
			(stroke
				(width 0.1)
				(type default)
			)
			(layer "F.Fab")
		)
		(pad "1" smd circle
			(at -0.40005 0 270)
			(size 0 0)
			(layers "F.Cu" "F.Mask" "F.Paste")
			(net "SW_PVDD_33_S5_BST_R")
		)
		(pad "2" smd circle
			(at 0.40005 0 270)
			(size 0 0)
			(layers "F.Cu" "F.Mask" "F.Paste")
			(net "SW_PVDD_33_S5_SW")
		)
	)
)
